# T6G (Grand Teton) — schematic netlist excerpt (pin names and nets, part order shuffled) for the footprints in the layout excerpt that follows; sources: Cadence DE-HDL packaged netlist, KiCad conversion of 04192023_DAF0TMB3IC0_F0TG_MB_C_brd_V02_OCP.brd

C45  Q_CAP  1UF 25V 10% X6S  pkg C0402  page 187 : A = P1V5_BAT_IN ; B = GND
C6629  Q_CAP_DIFFBUS  DIFF BUS_0.22UF 6.3V 20% X6S  pkg C0201  page 319 : \1\ = P5E_CPU1_P0_TX_BUF_C_DP<0> ; \2\ = P5E_CPU1_P0_TX_BUF_DP<0>
PR4528  Q_RES  10M 1% CHIP  pkg 0402LF  page 146 : A = P12V_E1S_0 ; B = P12V_E1S_GATE_0

(kicad_pcb
	(version 20260206)
	(generator "pcbnew")
	(generator_version "10.0")
	(general
		(thickness 1.6)
		(legacy_teardrops no)
	)
	(paper "A4")
	(title_block
		(title "04192023_DAF0TMB3IC0_F0TG_MB_C_brd_V02_OCP.brd")
		(comment 1 "Grand Teton / footprints 3676-3678 of 8354")
	)
	(layers
		(0 "F.Cu" signal "TOP")
		(4 "In1.Cu" signal "GND")
		(6 "In2.Cu" signal "IN1")
		(8 "In3.Cu" signal "GND1")
		(10 "In4.Cu" signal "IN2")
		(12 "In5.Cu" signal "GND2")
		(14 "In6.Cu" signal "IN3")
		(16 "In7.Cu" signal "GND3")
		(18 "In8.Cu" signal "VCC")
		(20 "In9.Cu" signal "VCC1")
		(22 "In10.Cu" signal "GND4")
		(24 "In11.Cu" signal "IN4")
		(26 "In12.Cu" signal "GND5")
		(28 "In13.Cu" signal "IN5")
		(30 "In14.Cu" signal "GND6")
		(32 "In15.Cu" signal "IN6")
		(34 "In16.Cu" signal "GND7")
		(2 "B.Cu" signal "BOTTOM")
		(9 "F.Adhes" user "F.Adhesive")
		(11 "B.Adhes" user "B.Adhesive")
		(13 "F.Paste" user "Package Geometry/Pastemask Top")
		(15 "B.Paste" user "Package Geometry/Pastemask Bottom")
		(5 "F.SilkS" user "Ref Des/Silkscreen Top")
		(7 "B.SilkS" user "Ref Des/Silkscreen Bottom")
		(1 "F.Mask" user "Board Geometry/Soldermask Top")
		(3 "B.Mask" user "Board Geometry/Soldermask Bottom")
		(17 "Dwgs.User" user "User.Drawings")
		(19 "Cmts.User" user "User.Comments")
		(21 "Eco1.User" user "User.Eco1")
		(23 "Eco2.User" user "User.Eco2")
		(25 "Edge.Cuts" user "Board Geometry/Outline")
		(27 "Margin" user)
		(31 "F.CrtYd" user "Package Geometry/Place Bound Top")
		(29 "B.CrtYd" user "Package Geometry/Place Bound Bottom")
		(35 "F.Fab" user "Ref Des/Assembly Top")
		(33 "B.Fab" user "Ref Des/Assembly Bottom")
	)
	(footprint ""
		(layer "F.Cu")
		(at 256.87274 -39.082472)
		(property "Reference" "PR4528"
			(at 0 0 0)
			(layer "F.SilkS")
			(hide yes)
			(effects
				(font
					(size 1.27 1.27)
				)
			)
		)
		(property "Value" ""
			(at 0 0 0)
			(layer "F.Fab")
			(effects
				(font
					(size 1.27 1.27)
				)
			)
		)
		(duplicate_pad_numbers_are_jumpers no)
		(fp_line
			(start -0.7874 -0.4064)
			(end 0.7874 -0.4064)
			(stroke
				(width 0.1524)
				(type default)
			)
			(layer "F.SilkS")
		)
		(fp_line
			(start -0.7874 0.4064)
			(end -0.7874 -0.4064)
			(stroke
				(width 0.1524)
				(type default)
			)
			(layer "F.SilkS")
		)
		(fp_line
			(start 0.7874 -0.4064)
			(end 0.7874 0.4064)
			(stroke
				(width 0.1524)
				(type default)
			)
			(layer "F.SilkS")
		)
		(fp_line
			(start 0.7874 0.4064)
			(end -0.7874 0.4064)
			(stroke
				(width 0.1524)
				(type default)
			)
			(layer "F.SilkS")
		)
		(fp_line
			(start -0.67945 -0.305054)
			(end -0.12065 -0.305054)
			(stroke
				(width 0.1)
				(type default)
			)
			(layer "F.Fab")
		)
		(fp_line
			(start -0.67945 0.3048)
			(end -0.67945 -0.305054)
			(stroke
				(width 0.1)
				(type default)
			)
			(layer "F.Fab")
		)
		(fp_line
			(start -0.12065 -0.305054)
			(end -0.12065 -0.2794)
			(stroke
				(width 0.1)
				(type default)
			)
			(layer "F.Fab")
		)
		(fp_line
			(start -0.12065 -0.2794)
			(end 0.12065 -0.2794)
			(stroke
				(width 0.1)
				(type default)
			)
			(layer "F.Fab")
		)
		(fp_line
			(start -0.12065 0.2794)
			(end -0.12065 0.3048)
			(stroke
				(width 0.1)
				(type default)
			)
			(layer "F.Fab")
		)
		(fp_line
			(start -0.12065 0.3048)
			(end -0.67945 0.3048)
			(stroke
				(width 0.1)
				(type default)
			)
			(layer "F.Fab")
		)
		(fp_line
			(start 0.120396 0.2794)
			(end -0.12065 0.2794)
			(stroke
				(width 0.1)
				(type default)
			)
			(layer "F.Fab")
		)
		(fp_line
			(start 0.120396 0.3048)
			(end 0.120396 0.2794)
			(stroke
				(width 0.1)
				(type default)
			)
			(layer "F.Fab")
		)
		(fp_line
			(start 0.12065 -0.3048)
			(end 0.67945 -0.3048)
			(stroke
				(width 0.1)
				(type default)
			)
			(layer "F.Fab")
		)
		(fp_line
			(start 0.12065 -0.2794)
			(end 0.12065 -0.3048)
			(stroke
				(width 0.1)
				(type default)
			)
			(layer "F.Fab")
		)
		(fp_line
			(start 0.67945 -0.3048)
			(end 0.67945 0.3048)
			(stroke
				(width 0.1)
				(type default)
			)
			(layer "F.Fab")
		)
		(fp_line
			(start 0.67945 0.3048)
			(end 0.120396 0.3048)
			(stroke
				(width 0.1)
				(type default)
			)
			(layer "F.Fab")
		)
		(pad "1" smd circle
			(at -0.40005 0)
			(size 0 0)
			(layers "F.Cu" "F.Mask" "F.Paste")
			(net "P12V_E1S_0")
		)
		(pad "2" smd circle
			(at 0.40005 0)
			(size 0 0)
			(layers "F.Cu" "F.Mask" "F.Paste")
			(net "P12V_E1S_GATE_0")
		)
	)
	(footprint ""
		(layer "F.Cu")
		(at 48.683164 -408.517344 -90)
		(property "Reference" "C6629"
			(at 0 0 270)
			(layer "F.SilkS")
			(hide yes)
			(effects
				(font
					(size 1.27 1.27)
				)
			)
		)
		(property "Value" ""
			(at 0 0 270)
			(layer "F.Fab")
			(effects
				(font
					(size 1.27 1.27)
				)
			)
		)
		(duplicate_pad_numbers_are_jumpers no)
		(fp_line
			(start -0.299974 0.150114)
			(end -0.299974 -0.150114)
			(stroke
				(width 0.1)
				(type default)
			)
			(layer "F.Fab")
		)
		(fp_line
			(start 0.299974 0.150114)
			(end -0.299974 0.150114)
			(stroke
				(width 0.1)
				(type default)
			)
			(layer "F.Fab")
		)
		(fp_line
			(start -0.299974 -0.150114)
			(end 0.299974 -0.150114)
			(stroke
				(width 0.1)
				(type default)
			)
			(layer "F.Fab")
		)
		(fp_line
			(start 0.299974 -0.150114)
			(end 0.299974 0.150114)
			(stroke
				(width 0.1)
				(type default)
			)
			(layer "F.Fab")
		)
		(pad "1" smd rect
			(at -0.2667 0 270)
			(size 0.3048 0.381)
			(layers "F.Cu" "F.Mask" "F.Paste")
			(net "P5E_CPU1_P0_TX_BUF_C_DP<0>")
		)
		(pad "2" smd rect
			(at 0.2667 0 270)
			(size 0.3048 0.381)
			(layers "F.Cu" "F.Mask" "F.Paste")
			(net "P5E_CPU1_P0_TX_BUF_DP<0>")
		)
	)
	(footprint ""
		(layer "F.Cu")
		(at 298.050966 -23.763224)
		(property "Reference" "C45"
			(at 0 0 0)
			(layer "F.SilkS")
			(hide yes)
			(effects
				(font
					(size 1.27 1.27)
				)
			)
		)
		(property "Value" ""
			(at 0 0 0)
			(layer "F.Fab")
			(effects
				(font
					(size 1.27 1.27)
				)
			)
		)
		(duplicate_pad_numbers_are_jumpers no)
		(fp_line
			(start -0.7874 -0.4064)
			(end 0.7874 -0.4064)
			(stroke
				(width 0.1524)
				(type default)
			)
			(layer "F.SilkS")
		)
		(fp_line
			(start -0.7874 0.4064)
			(end -0.7874 -0.4064)
			(stroke
				(width 0.1524)
				(type default)
			)
			(layer "F.SilkS")
		)
		(fp_line
			(start 0.7874 -0.4064)
			(end 0.7874 0.4064)
			(stroke
				(width 0.1524)
				(type default)
			)
			(layer "F.SilkS")
		)
		(fp_line
			(start 0.7874 0.4064)
			(end -0.7874 0.4064)
			(stroke
				(width 0.1524)
				(type default)
			)
			(layer "F.SilkS")
		)
		(fp_line
			(start -0.67945 -0.305054)
			(end -0.12065 -0.305054)
			(stroke
				(width 0.1)
				(type default)
			)
			(layer "F.Fab")
		)
		(fp_line
			(start -0.67945 0.3048)
			(end -0.67945 -0.305054)
			(stroke
				(width 0.1)
				(type default)
			)
			(layer "F.Fab")
		)
		(fp_line
			(start -0.12065 -0.305054)
			(end -0.12065 -0.2794)
			(stroke
				(width 0.1)
				(type default)
			)
			(layer "F.Fab")
		)
		(fp_line
			(start -0.12065 -0.2794)
			(end 0.12065 -0.2794)
			(stroke
				(width 0.1)
				(type default)
			)
			(layer "F.Fab")
		)
		(fp_line
			(start -0.12065 0.2794)
			(end -0.12065 0.3048)
			(stroke
				(width 0.1)
				(type default)
			)
			(layer "F.Fab")
		)
		(fp_line
			(start -0.12065 0.3048)
			(end -0.67945 0.3048)
			(stroke
				(width 0.1)
				(type default)
			)
			(layer "F.Fab")
		)
		(fp_line
			(start 0.120396 0.2794)
			(end -0.12065 0.2794)
			(stroke
				(width 0.1)
				(type default)
			)
			(layer "F.Fab")
		)
		(fp_line
			(start 0.120396 0.3048)
			(end 0.120396 0.2794)
			(stroke
				(width 0.1)
				(type default)
			)
			(layer "F.Fab")
		)
		(fp_line
			(start 0.12065 -0.3048)
			(end 0.67945 -0.3048)
			(stroke
				(width 0.1)
				(type default)
			)
			(layer "F.Fab")
		)
		(fp_line
			(start 0.12065 -0.2794)
			(end 0.12065 -0.3048)
			(stroke
				(width 0.1)
				(type default)
			)
			(layer "F.Fab")
		)
		(fp_line
			(start 0.67945 -0.3048)
			(end 0.67945 0.3048)
			(stroke
				(width 0.1)
				(type default)
			)
			(layer "F.Fab")
		)
		(fp_line
			(start 0.67945 0.3048)
			(end 0.120396 0.3048)
			(stroke
				(width 0.1)
				(type default)
			)
			(layer "F.Fab")
		)
		(pad "1" smd circle
			(at -0.40005 0)
			(size 0 0)
			(layers "F.Cu" "F.Mask" "F.Paste")
			(net "P1V5_BAT_IN")
		)
		(pad "2" smd circle
			(at 0.40005 0)
			(size 0 0)
			(layers "F.Cu" "F.Mask" "F.Paste")
			(net "GND")
		)
	)
)
